(kicad_pcb
	(version 20260206)
	(generator "pcbnew")
	(generator_version "10.0")
	(general
		(thickness 1.6)
		(legacy_teardrops no)
	)
	(paper "A4")
	(title_block
		(title "fcb — 12433-1M.1206WZS1330.brd")
		(comment 1 "Open Vault / Knox (Wiwynn) / footprints 51-57 of 495")
	)
	(layers
		(0 "F.Cu" signal "TOP")
		(4 "In1.Cu" signal "L2GND")
		(6 "In2.Cu" signal "L3VCC")
		(2 "B.Cu" signal "BOTTOM")
		(9 "F.Adhes" user "F.Adhesive")
		(11 "B.Adhes" user "B.Adhesive")
		(13 "F.Paste" user "Package Geometry/Pastemask Top")
		(15 "B.Paste" user "Package Geometry/Pastemask Bottom")
		(5 "F.SilkS" user "Ref Des/Silkscreen Top")
		(7 "B.SilkS" user "Ref Des/Silkscreen Bottom")
		(1 "F.Mask" user "Board Geometry/Soldermask Top")
		(3 "B.Mask" user "Board Geometry/Soldermask Bottom")
		(17 "Dwgs.User" user "User.Drawings")
		(19 "Cmts.User" user "User.Comments")
		(21 "Eco1.User" user "User.Eco1")
		(23 "Eco2.User" user "User.Eco2")
		(25 "Edge.Cuts" user "Board Geometry/Outline")
		(27 "Margin" user)
		(31 "F.CrtYd" user "Package Geometry/Place Bound Top")
		(29 "B.CrtYd" user "Package Geometry/Place Bound Bottom")
		(35 "F.Fab" user "Ref Des/Assembly Top")
		(33 "B.Fab" user "Ref Des/Assembly Bottom")
	)
	(footprint ""
		(layer "F.Cu")
		(at 13.2588 -61.3918)
		(property "Reference" "C31"
			(at 0 0 0)
			(layer "F.SilkS")
			(hide yes)
			(effects
				(font
					(size 1.27 1.27)
				)
			)
		)
		(property "Value" "SCD1U50V3KX-GP"
			(at 0 -2.8194 0)
			(unlocked yes)
			(layer "F.Fab")
			(hide yes)
			(effects
				(font
					(size 1.016 1.016)
					(thickness 0.1524)
				)
			)
		)
		(property "Device Type" "C603H36"
			(at 0 -4.3434 0)
			(unlocked yes)
			(layer "F.Fab")
			(hide yes)
			(effects
				(font
					(size 1.016 1.016)
					(thickness 0.1524)
				)
			)
		)
		(duplicate_pad_numbers_are_jumpers no)
		(fp_line
			(start 0.508 0)
			(end -0.508 0)
			(stroke
				(width 0.2032)
				(type default)
			)
			(layer "F.SilkS")
		)
		(fp_rect
			(start -0.5842 1.3335)
			(end 0.5842 -1.3335)
			(stroke
				(width 0)
				(type default)
			)
			(fill no)
			(layer "F.CrtYd")
		)
		(fp_rect
			(start -0.5842 1.3335)
			(end 0.5842 -1.3335)
			(stroke
				(width 0)
				(type default)
			)
			(fill no)
			(layer "F.Fab")
		)
		(pad "1" smd custom
			(at 0 -0.762)
			(size 0.2159 0.2159)
			(layers "F.Cu" "F.Mask" "F.Paste")
			(net "P12V")
			(options
				(clearance outline)
				(anchor circle)
			)
			(primitives
				(gr_poly
					(pts
						(arc
							(start -0.3302 -0.4318)
							(mid -0.402042 -0.402042)
							(end -0.4318 -0.3302)
						)
						(arc
							(start -0.4318 0.3302)
							(mid -0.402042 0.402042)
							(end -0.3302 0.4318)
						)
						(arc
							(start 0.3302 0.4318)
							(mid 0.402042 0.402042)
							(end 0.4318 0.3302)
						)
						(arc
							(start 0.4318 -0.3302)
							(mid 0.402042 -0.402042)
							(end 0.3302 -0.4318)
						)
					)
					(width 0)
					(fill yes)
				)
			)
		)
		(pad "2" smd custom
			(at 0 0.762)
			(size 0.2159 0.2159)
			(layers "F.Cu" "F.Mask" "F.Paste")
			(net "GND")
			(options
				(clearance outline)
				(anchor circle)
			)
			(primitives
				(gr_poly
					(pts
						(arc
							(start -0.3302 -0.4318)
							(mid -0.402042 -0.402042)
							(end -0.4318 -0.3302)
						)
						(arc
							(start -0.4318 0.3302)
							(mid -0.402042 0.402042)
							(end -0.3302 0.4318)
						)
						(arc
							(start 0.3302 0.4318)
							(mid 0.402042 0.402042)
							(end 0.4318 0.3302)
						)
						(arc
							(start 0.4318 -0.3302)
							(mid 0.402042 -0.402042)
							(end 0.3302 -0.4318)
						)
					)
					(width 0)
					(fill yes)
				)
			)
		)
	)
	(footprint ""
		(layer "F.Cu")
		(at 43.2308 -158.8516)
		(property "Reference" "R51"
			(at 0 0 0)
			(layer "F.SilkS")
			(hide yes)
			(effects
				(font
					(size 1.27 1.27)
				)
			)
		)
		(property "Value" "0R2J-2-GP"
			(at 0.064008 -3.993896 0)
			(unlocked yes)
			(layer "F.Fab")
			(hide yes)
			(effects
				(font
					(size 1.016 1.016)
					(thickness 0.1524)
				)
			)
		)
		(property "Device Type" "R402H16"
			(at 0.064008 -5.517896 0)
			(unlocked yes)
			(layer "F.Fab")
			(hide yes)
			(effects
				(font
					(size 1.016 1.016)
					(thickness 0.1524)
				)
			)
		)
		(duplicate_pad_numbers_are_jumpers no)
		(fp_line
			(start -0.508 -0.9398)
			(end -0.508 0.9398)
			(stroke
				(width 0.1524)
				(type default)
			)
			(layer "F.SilkS")
		)
		(fp_line
			(start 0.508 -0.9398)
			(end -0.508 -0.9398)
			(stroke
				(width 0.1524)
				(type default)
			)
			(layer "F.SilkS")
		)
		(fp_rect
			(start -0.508 0.9398)
			(end 0.508 -0.9398)
			(stroke
				(width 0)
				(type default)
			)
			(fill no)
			(layer "F.CrtYd")
		)
		(fp_rect
			(start -0.508 0.9398)
			(end 0.508 -0.9398)
			(stroke
				(width 0)
				(type default)
			)
			(fill no)
			(layer "F.Fab")
		)
		(pad "1" smd custom
			(at 0 -0.4445)
			(size 0.1397 0.1397)
			(layers "F.Cu" "F.Mask" "F.Paste")
			(net "NCT7904_VSEN_P12V_AUX")
			(options
				(clearance outline)
				(anchor circle)
			)
			(primitives
				(gr_poly
					(pts
						(arc
							(start -0.1778 -0.2794)
							(mid -0.249642 -0.249642)
							(end -0.2794 -0.1778)
						)
						(arc
							(start -0.2794 0.1778)
							(mid -0.249642 0.249642)
							(end -0.1778 0.2794)
						)
						(arc
							(start 0.1778 0.2794)
							(mid 0.249642 0.249642)
							(end 0.2794 0.1778)
						)
						(arc
							(start 0.2794 -0.1778)
							(mid 0.249642 -0.249642)
							(end 0.1778 -0.2794)
						)
					)
					(width 0)
					(fill yes)
				)
			)
		)
		(pad "2" smd custom
			(at 0 0.4445)
			(size 0.1397 0.1397)
			(layers "F.Cu" "F.Mask" "F.Paste")
			(net "NCT7904_VSEN9")
			(options
				(clearance outline)
				(anchor circle)
			)
			(primitives
				(gr_poly
					(pts
						(arc
							(start -0.1778 -0.2794)
							(mid -0.249642 -0.249642)
							(end -0.2794 -0.1778)
						)
						(arc
							(start -0.2794 0.1778)
							(mid -0.249642 0.249642)
							(end -0.1778 0.2794)
						)
						(arc
							(start 0.1778 0.2794)
							(mid 0.249642 0.249642)
							(end 0.2794 0.1778)
						)
						(arc
							(start 0.2794 -0.1778)
							(mid 0.249642 -0.249642)
							(end 0.1778 -0.2794)
						)
					)
					(width 0)
					(fill yes)
				)
			)
		)
	)
	(footprint ""
		(layer "F.Cu")
		(at 38.862 -240.665 180)
		(property "Reference" "R156"
			(at 0 0 180)
			(layer "F.SilkS")
			(hide yes)
			(effects
				(font
					(size 1.27 1.27)
				)
			)
		)
		(property "Value" "330R2J-3-GP"
			(at 0.064008 -3.993896 180)
			(unlocked yes)
			(layer "F.Fab")
			(hide yes)
			(effects
				(font
					(size 1.016 1.016)
					(thickness 0.1524)
				)
			)
		)
		(property "Device Type" "R402H16"
			(at 0.064008 -5.517896 180)
			(unlocked yes)
			(layer "F.Fab")
			(hide yes)
			(effects
				(font
					(size 1.016 1.016)
					(thickness 0.1524)
				)
			)
		)
		(duplicate_pad_numbers_are_jumpers no)
		(fp_line
			(start 0.508 -0.9398)
			(end -0.508 -0.9398)
			(stroke
				(width 0.1524)
				(type default)
			)
			(layer "F.SilkS")
		)
		(fp_line
			(start -0.508 -0.9398)
			(end -0.508 0.9398)
			(stroke
				(width 0.1524)
				(type default)
			)
			(layer "F.SilkS")
		)
		(fp_rect
			(start -0.508 0.9398)
			(end 0.508 -0.9398)
			(stroke
				(width 0)
				(type default)
			)
			(fill no)
			(layer "F.CrtYd")
		)
		(fp_rect
			(start -0.508 0.9398)
			(end 0.508 -0.9398)
			(stroke
				(width 0)
				(type default)
			)
			(fill no)
			(layer "F.Fab")
		)
		(pad "1" smd custom
			(at 0 -0.4445 180)
			(size 0.1397 0.1397)
			(layers "F.Cu" "F.Mask" "F.Paste")
			(net "P3V3")
			(options
				(clearance outline)
				(anchor circle)
			)
			(primitives
				(gr_poly
					(pts
						(arc
							(start -0.1778 -0.2794)
							(mid -0.249642 -0.249642)
							(end -0.2794 -0.1778)
						)
						(arc
							(start -0.2794 0.1778)
							(mid -0.249642 0.249642)
							(end -0.1778 0.2794)
						)
						(arc
							(start 0.1778 0.2794)
							(mid 0.249642 0.249642)
							(end 0.2794 0.1778)
						)
						(arc
							(start 0.2794 -0.1778)
							(mid 0.249642 -0.249642)
							(end 0.1778 -0.2794)
						)
					)
					(width 0)
					(fill yes)
				)
			)
		)
		(pad "2" smd custom
			(at 0 0.4445 180)
			(size 0.1397 0.1397)
			(layers "F.Cu" "F.Mask" "F.Paste")
			(net "LED_DR_LED2")
			(options
				(clearance outline)
				(anchor circle)
			)
			(primitives
				(gr_poly
					(pts
						(arc
							(start -0.1778 -0.2794)
							(mid -0.249642 -0.249642)
							(end -0.2794 -0.1778)
						)
						(arc
							(start -0.2794 0.1778)
							(mid -0.249642 0.249642)
							(end -0.1778 0.2794)
						)
						(arc
							(start 0.1778 0.2794)
							(mid 0.249642 0.249642)
							(end 0.2794 0.1778)
						)
						(arc
							(start 0.2794 -0.1778)
							(mid 0.249642 -0.249642)
							(end 0.1778 -0.2794)
						)
					)
					(width 0)
					(fill yes)
				)
			)
		)
	)
	(footprint ""
		(layer "F.Cu")
		(at 32.399224 -173.65091 90)
		(property "Reference" "R17"
			(at 0 0 90)
			(layer "F.SilkS")
			(hide yes)
			(effects
				(font
					(size 1.27 1.27)
				)
			)
		)
		(property "Value" "100KR2F-L1-GP"
			(at 0.064008 -3.993896 90)
			(unlocked yes)
			(layer "F.Fab")
			(hide yes)
			(effects
				(font
					(size 1.016 1.016)
					(thickness 0.1524)
				)
			)
		)
		(property "Device Type" "R402H16"
			(at 0.064008 -5.517896 90)
			(unlocked yes)
			(layer "F.Fab")
			(hide yes)
			(effects
				(font
					(size 1.016 1.016)
					(thickness 0.1524)
				)
			)
		)
		(duplicate_pad_numbers_are_jumpers no)
		(fp_line
			(start 0.508 -0.9398)
			(end -0.508 -0.9398)
			(stroke
				(width 0.1524)
				(type default)
			)
			(layer "F.SilkS")
		)
		(fp_line
			(start -0.508 -0.9398)
			(end -0.508 0.9398)
			(stroke
				(width 0.1524)
				(type default)
			)
			(layer "F.SilkS")
		)
		(fp_rect
			(start -0.508 0.9398)
			(end 0.508 -0.9398)
			(stroke
				(width 0)
				(type default)
			)
			(fill no)
			(layer "F.CrtYd")
		)
		(fp_rect
			(start -0.508 0.9398)
			(end 0.508 -0.9398)
			(stroke
				(width 0)
				(type default)
			)
			(fill no)
			(layer "F.Fab")
		)
		(pad "1" smd custom
			(at 0 -0.4445 90)
			(size 0.1397 0.1397)
			(layers "F.Cu" "F.Mask" "F.Paste")
			(net "PWM_EXP_1A")
			(options
				(clearance outline)
				(anchor circle)
			)
			(primitives
				(gr_poly
					(pts
						(arc
							(start -0.1778 -0.2794)
							(mid -0.249642 -0.249642)
							(end -0.2794 -0.1778)
						)
						(arc
							(start -0.2794 0.1778)
							(mid -0.249642 0.249642)
							(end -0.1778 0.2794)
						)
						(arc
							(start 0.1778 0.2794)
							(mid 0.249642 0.249642)
							(end 0.2794 0.1778)
						)
						(arc
							(start 0.2794 -0.1778)
							(mid 0.249642 -0.249642)
							(end 0.1778 -0.2794)
						)
					)
					(width 0)
					(fill yes)
				)
			)
		)
		(pad "2" smd custom
			(at 0 0.4445 90)
			(size 0.1397 0.1397)
			(layers "F.Cu" "F.Mask" "F.Paste")
			(net "GND")
			(options
				(clearance outline)
				(anchor circle)
			)
			(primitives
				(gr_poly
					(pts
						(arc
							(start -0.1778 -0.2794)
							(mid -0.249642 -0.249642)
							(end -0.2794 -0.1778)
						)
						(arc
							(start -0.2794 0.1778)
							(mid -0.249642 0.249642)
							(end -0.1778 0.2794)
						)
						(arc
							(start 0.1778 0.2794)
							(mid 0.249642 0.249642)
							(end 0.2794 0.1778)
						)
						(arc
							(start 0.2794 -0.1778)
							(mid 0.249642 -0.249642)
							(end 0.1778 -0.2794)
						)
					)
					(width 0)
					(fill yes)
				)
			)
		)
	)
	(footprint ""
		(layer "F.Cu")
		(at 23.622 -365.506 90)
		(property "Reference" "PR1"
			(at 0 0 90)
			(layer "F.SilkS")
			(hide yes)
			(effects
				(font
					(size 1.27 1.27)
				)
			)
		)
		(property "Value" "100KR2F-L1-GP"
			(at 0.064008 -3.993896 90)
			(unlocked yes)
			(layer "F.Fab")
			(hide yes)
			(effects
				(font
					(size 1.016 1.016)
					(thickness 0.1524)
				)
			)
		)
		(property "Device Type" "R402H16"
			(at 0.064008 -5.517896 90)
			(unlocked yes)
			(layer "F.Fab")
			(hide yes)
			(effects
				(font
					(size 1.016 1.016)
					(thickness 0.1524)
				)
			)
		)
		(duplicate_pad_numbers_are_jumpers no)
		(fp_line
			(start 0.508 -0.9398)
			(end -0.508 -0.9398)
			(stroke
				(width 0.1524)
				(type default)
			)
			(layer "F.SilkS")
		)
		(fp_line
			(start -0.508 -0.9398)
			(end -0.508 0.9398)
			(stroke
				(width 0.1524)
				(type default)
			)
			(layer "F.SilkS")
		)
		(fp_rect
			(start -0.508 0.9398)
			(end 0.508 -0.9398)
			(stroke
				(width 0)
				(type default)
			)
			(fill no)
			(layer "F.CrtYd")
		)
		(fp_rect
			(start -0.508 0.9398)
			(end 0.508 -0.9398)
			(stroke
				(width 0)
				(type default)
			)
			(fill no)
			(layer "F.Fab")
		)
		(pad "1" smd custom
			(at 0 -0.4445 90)
			(size 0.1397 0.1397)
			(layers "F.Cu" "F.Mask" "F.Paste")
			(net "ADM1276_VCAP")
			(options
				(clearance outline)
				(anchor circle)
			)
			(primitives
				(gr_poly
					(pts
						(arc
							(start -0.1778 -0.2794)
							(mid -0.249642 -0.249642)
							(end -0.2794 -0.1778)
						)
						(arc
							(start -0.2794 0.1778)
							(mid -0.249642 0.249642)
							(end -0.1778 0.2794)
						)
						(arc
							(start 0.1778 0.2794)
							(mid 0.249642 0.249642)
							(end 0.2794 0.1778)
						)
						(arc
							(start 0.2794 -0.1778)
							(mid 0.249642 -0.249642)
							(end 0.1778 -0.2794)
						)
					)
					(width 0)
					(fill yes)
				)
			)
		)
		(pad "2" smd custom
			(at 0 0.4445 90)
			(size 0.1397 0.1397)
			(layers "F.Cu" "F.Mask" "F.Paste")
			(net "ADM1276_ISET")
			(options
				(clearance outline)
				(anchor circle)
			)
			(primitives
				(gr_poly
					(pts
						(arc
							(start -0.1778 -0.2794)
							(mid -0.249642 -0.249642)
							(end -0.2794 -0.1778)
						)
						(arc
							(start -0.2794 0.1778)
							(mid -0.249642 0.249642)
							(end -0.1778 0.2794)
						)
						(arc
							(start 0.1778 0.2794)
							(mid 0.249642 0.249642)
							(end 0.2794 0.1778)
						)
						(arc
							(start 0.2794 -0.1778)
							(mid 0.249642 -0.249642)
							(end 0.1778 -0.2794)
						)
					)
					(width 0)
					(fill yes)
				)
			)
		)
	)
	(footprint ""
		(layer "F.Cu")
		(at 9.4488 -74.7522 -90)
		(property "Reference" "C23"
			(at 0 0 270)
			(layer "F.SilkS")
			(hide yes)
			(effects
				(font
					(size 1.27 1.27)
				)
			)
		)
		(property "Value" "SCD1U50V3KX-GP"
			(at 0 -2.8194 270)
			(unlocked yes)
			(layer "F.Fab")
			(hide yes)
			(effects
				(font
					(size 1.016 1.016)
					(thickness 0.1524)
				)
			)
		)
		(property "Device Type" "C603H36"
			(at 0 -4.3434 270)
			(unlocked yes)
			(layer "F.Fab")
			(hide yes)
			(effects
				(font
					(size 1.016 1.016)
					(thickness 0.1524)
				)
			)
		)
		(duplicate_pad_numbers_are_jumpers no)
		(fp_line
			(start 0.508 0)
			(end -0.508 0)
			(stroke
				(width 0.2032)
				(type default)
			)
			(layer "F.SilkS")
		)
		(fp_rect
			(start -0.5842 1.3335)
			(end 0.5842 -1.3335)
			(stroke
				(width 0)
				(type default)
			)
			(fill no)
			(layer "F.CrtYd")
		)
		(fp_rect
			(start -0.5842 1.3335)
			(end 0.5842 -1.3335)
			(stroke
				(width 0)
				(type default)
			)
			(fill no)
			(layer "F.Fab")
		)
		(pad "1" smd custom
			(at 0 -0.762 270)
			(size 0.2159 0.2159)
			(layers "F.Cu" "F.Mask" "F.Paste")
			(net "P12VU")
			(options
				(clearance outline)
				(anchor circle)
			)
			(primitives
				(gr_poly
					(pts
						(arc
							(start -0.3302 -0.4318)
							(mid -0.402042 -0.402042)
							(end -0.4318 -0.3302)
						)
						(arc
							(start -0.4318 0.3302)
							(mid -0.402042 0.402042)
							(end -0.3302 0.4318)
						)
						(arc
							(start 0.3302 0.4318)
							(mid 0.402042 0.402042)
							(end 0.4318 0.3302)
						)
						(arc
							(start 0.4318 -0.3302)
							(mid 0.402042 -0.402042)
							(end 0.3302 -0.4318)
						)
					)
					(width 0)
					(fill yes)
				)
			)
		)
		(pad "2" smd custom
			(at 0 0.762 270)
			(size 0.2159 0.2159)
			(layers "F.Cu" "F.Mask" "F.Paste")
			(net "GND")
			(options
				(clearance outline)
				(anchor circle)
			)
			(primitives
				(gr_poly
					(pts
						(arc
							(start -0.3302 -0.4318)
							(mid -0.402042 -0.402042)
							(end -0.4318 -0.3302)
						)
						(arc
							(start -0.4318 0.3302)
							(mid -0.402042 0.402042)
							(end -0.3302 0.4318)
						)
						(arc
							(start 0.3302 0.4318)
							(mid 0.402042 0.402042)
							(end 0.4318 0.3302)
						)
						(arc
							(start 0.4318 -0.3302)
							(mid 0.402042 -0.402042)
							(end 0.3302 -0.4318)
						)
					)
					(width 0)
					(fill yes)
				)
			)
		)
	)
	(footprint ""
		(layer "F.Cu")
		(at 45.81271 -163.594034)
		(property "Reference" "R3"
			(at 0 0 0)
			(layer "F.SilkS")
			(hide yes)
			(effects
				(font
					(size 1.27 1.27)
				)
			)
		)
		(property "Value" "4K7R2F-GP"
			(at 0.064008 -3.993896 0)
			(unlocked yes)
			(layer "F.Fab")
			(hide yes)
			(effects
				(font
					(size 1.016 1.016)
					(thickness 0.1524)
				)
			)
		)
		(property "Device Type" "R402H16"
			(at 0.064008 -5.517896 0)
			(unlocked yes)
			(layer "F.Fab")
			(hide yes)
			(effects
				(font
					(size 1.016 1.016)
					(thickness 0.1524)
				)
			)
		)
		(duplicate_pad_numbers_are_jumpers no)
		(fp_line
			(start -0.508 -0.9398)
			(end -0.508 0.9398)
			(stroke
				(width 0.1524)
				(type default)
			)
			(layer "F.SilkS")
		)
		(fp_line
			(start 0.508 -0.9398)
			(end -0.508 -0.9398)
			(stroke
				(width 0.1524)
				(type default)
			)
			(layer "F.SilkS")
		)
		(fp_rect
			(start -0.508 0.9398)
			(end 0.508 -0.9398)
			(stroke
				(width 0)
				(type default)
			)
			(fill no)
			(layer "F.CrtYd")
		)
		(fp_rect
			(start -0.508 0.9398)
			(end 0.508 -0.9398)
			(stroke
				(width 0)
				(type default)
			)
			(fill no)
			(layer "F.Fab")
		)
		(pad "1" smd custom
			(at 0 -0.4445)
			(size 0.1397 0.1397)
			(layers "F.Cu" "F.Mask" "F.Paste")
			(net "OSC_TRI_S")
			(options
				(clearance outline)
				(anchor circle)
			)
			(primitives
				(gr_poly
					(pts
						(arc
							(start -0.1778 -0.2794)
							(mid -0.249642 -0.249642)
							(end -0.2794 -0.1778)
						)
						(arc
							(start -0.2794 0.1778)
							(mid -0.249642 0.249642)
							(end -0.1778 0.2794)
						)
						(arc
							(start 0.1778 0.2794)
							(mid 0.249642 0.249642)
							(end 0.2794 0.1778)
						)
						(arc
							(start 0.2794 -0.1778)
							(mid 0.249642 -0.249642)
							(end 0.1778 -0.2794)
						)
					)
					(width 0)
					(fill yes)
				)
			)
		)
		(pad "2" smd custom
			(at 0 0.4445)
			(size 0.1397 0.1397)
			(layers "F.Cu" "F.Mask" "F.Paste")
			(net "P3V3")
			(options
				(clearance outline)
				(anchor circle)
			)
			(primitives
				(gr_poly
					(pts
						(arc
							(start -0.1778 -0.2794)
							(mid -0.249642 -0.249642)
							(end -0.2794 -0.1778)
						)
						(arc
							(start -0.2794 0.1778)
							(mid -0.249642 0.249642)
							(end -0.1778 0.2794)
						)
						(arc
							(start 0.1778 0.2794)
							(mid 0.249642 0.249642)
							(end 0.2794 0.1778)
						)
						(arc
							(start 0.2794 -0.1778)
							(mid 0.249642 -0.249642)
							(end 0.1778 -0.2794)
						)
					)
					(width 0)
					(fill yes)
				)
			)
		)
	)
)
